(kicad_pcb
	(version 20241229)
	(generator "pcbnew")
	(generator_version "9.0")
	(general
		(thickness 1.62)
		(legacy_teardrops no)
	)
	(paper "A3")
	(title_block
		(title "COM Express 7 Baseboard")
		(date "2025-02-04")
		(rev "1.1.2")
		(company "Antmicro Ltd")
		(comment 1 "www.antmicro.com")
		(comment 9 "footprints 20-24 of 802")
	)
	(layers
		(0 "F.Cu" signal)
		(4 "In1.Cu" signal)
		(6 "In2.Cu" signal)
		(8 "In3.Cu" signal)
		(10 "In4.Cu" signal)
		(12 "In5.Cu" signal)
		(14 "In6.Cu" signal)
		(2 "B.Cu" signal)
		(9 "F.Adhes" user "F.Adhesive")
		(11 "B.Adhes" user "B.Adhesive")
		(13 "F.Paste" user)
		(15 "B.Paste" user)
		(5 "F.SilkS" user "F.Silkscreen")
		(7 "B.SilkS" user "B.Silkscreen")
		(1 "F.Mask" user)
		(3 "B.Mask" user)
		(17 "Dwgs.User" user "User.Drawings")
		(19 "Cmts.User" user "User.Comments")
		(21 "Eco1.User" user "User.Eco1")
		(23 "Eco2.User" user "User.Eco2")
		(25 "Edge.Cuts" user)
		(27 "Margin" user)
		(31 "F.CrtYd" user "F.Courtyard")
		(29 "B.CrtYd" user "B.Courtyard")
		(35 "F.Fab" user)
		(33 "B.Fab" user)
	)
	(footprint "antmicro-footprints:SC-74-6_1.5x2.9mm_P0.95mm"
		(layer "F.Cu")
		(at 242.620708 78.135)
		(tags "sc74 sc-74 sot23-6 sot457 tsop6 tsop-6")
		(property "Reference" "U26"
			(at -1 2.625 0)
			(layer "F.SilkS")
			(effects
				(font
					(size 0.7 0.7)
					(thickness 0.15)
				)
				(justify left bottom)
			)
		)
		(property "Value" "74LVC1G157-Q100H_SOT457"
			(at 0.001 2.7 0)
			(layer "F.Fab")
			(effects
				(font
					(size 0.7 0.7)
					(thickness 0.15)
				)
				(justify left bottom)
			)
		)
		(property "Datasheet" "https://www.mouser.com/datasheet/2/916/74LVC1G157_Q100-1578792.pdf"
			(at 0 0 0)
			(layer "F.Fab")
			(hide yes)
			(effects
				(font
					(size 1.27 1.27)
					(thickness 0.15)
				)
			)
		)
		(property "Author" "Antmicro"
			(at 0 0 0)
			(layer "F.Fab")
			(hide yes)
			(effects
				(font
					(size 1 1)
					(thickness 0.15)
				)
			)
		)
		(property "License" "Apache-2.0"
			(at 0 0 0)
			(layer "F.Fab")
			(hide yes)
			(effects
				(font
					(size 1 1)
					(thickness 0.15)
				)
			)
		)
		(property "MPN" "74LVC1G157-Q100H"
			(at 0 0 0)
			(layer "F.Fab")
			(hide yes)
			(effects
				(font
					(size 1 1)
					(thickness 0.15)
				)
			)
		)
		(property "Manufacturer" "Nexperia"
			(at 0 0 0)
			(layer "F.Fab")
			(hide yes)
			(effects
				(font
					(size 1 1)
					(thickness 0.15)
				)
			)
		)
		(sheetname "Misc")
		(sheetfile "misc.kicad_sch")
		(attr smd)
		(fp_circle
			(center -1.11 -1.454)
			(end -1.06 -1.454)
			(stroke
				(width 0.15)
				(type solid)
			)
			(fill yes)
			(layer "F.SilkS")
		)
		(fp_rect
			(start -1.7 -1.7)
			(end 1.7 1.7)
			(stroke
				(width 0.05)
				(type solid)
			)
			(fill no)
			(layer "F.CrtYd")
		)
		(fp_line
			(start -1.269 -0.915)
			(end -1.269 1.372)
			(stroke
				(width 0.15)
				(type solid)
			)
			(layer "F.Fab")
		)
		(fp_line
			(start -1.269 1.372)
			(end -1.167 1.372)
			(stroke
				(width 0.15)
				(type solid)
			)
			(layer "F.Fab")
		)
		(fp_line
			(start -1.167 1.372)
			(end 1.22 1.372)
			(stroke
				(width 0.15)
				(type solid)
			)
			(layer "F.Fab")
		)
		(fp_line
			(start -0.76 -1.422)
			(end -1.269 -0.915)
			(stroke
				(width 0.15)
				(type solid)
			)
			(layer "F.Fab")
		)
		(fp_line
			(start 1.22 -1.422)
			(end -0.76 -1.422)
			(stroke
				(width 0.15)
				(type solid)
			)
			(layer "F.Fab")
		)
		(fp_line
			(start 1.22 1.372)
			(end 1.22 -1.422)
			(stroke
				(width 0.15)
				(type solid)
			)
			(layer "F.Fab")
		)
		(pad "1" smd roundrect
			(at -1.2 -0.95)
			(size 0.8 0.55)
			(layers "F.Cu" "F.Mask" "F.Paste")
			(roundrect_rratio 0.15)
			(net 400 "/Com Express 7 MGMT/FAN_PWM")
			(pinfunction "I1")
			(pintype "input")
			(teardrops
				(best_length_ratio 0.2)
				(max_length 1)
				(best_width_ratio 0.9)
				(max_width 2)
				(curved_edges yes)
				(filter_ratio 0.9)
				(enabled yes)
				(allow_two_segments yes)
				(prefer_zone_connections yes)
			)
		)
		(pad "2" smd roundrect
			(at -1.2 0)
			(size 0.8 0.55)
			(layers "F.Cu" "F.Mask" "F.Paste")
			(roundrect_rratio 0.15)
			(net 1 "GND")
			(pinfunction "GND")
			(pintype "power_in")
			(teardrops
				(best_length_ratio 0.2)
				(max_length 1)
				(best_width_ratio 0.9)
				(max_width 2)
				(curved_edges yes)
				(filter_ratio 0.9)
				(enabled yes)
				(allow_two_segments yes)
				(prefer_zone_connections yes)
			)
		)
		(pad "3" smd roundrect
			(at -1.2 0.95)
			(size 0.8 0.55)
			(layers "F.Cu" "F.Mask" "F.Paste")
			(roundrect_rratio 0.15)
			(net 596 "/Misc/PWM2")
			(pinfunction "I0")
			(pintype "input")
			(teardrops
				(best_length_ratio 0.2)
				(max_length 1)
				(best_width_ratio 0.9)
				(max_width 2)
				(curved_edges yes)
				(filter_ratio 0.9)
				(enabled yes)
				(allow_two_segments yes)
				(prefer_zone_connections yes)
			)
		)
		(pad "4" smd roundrect
			(at 1.2 0.95)
			(size 0.8 0.55)
			(layers "F.Cu" "F.Mask" "F.Paste")
			(roundrect_rratio 0.15)
			(net 783 "/Misc/PWM_{B3V3}")
			(pinfunction "Y")
			(pintype "output")
			(teardrops
				(best_length_ratio 0.2)
				(max_length 1)
				(best_width_ratio 0.9)
				(max_width 2)
				(curved_edges yes)
				(filter_ratio 0.9)
				(enabled yes)
				(allow_two_segments yes)
				(prefer_zone_connections yes)
			)
		)
		(pad "5" smd roundrect
			(at 1.2 0)
			(size 0.8 0.55)
			(layers "F.Cu" "F.Mask" "F.Paste")
			(roundrect_rratio 0.15)
			(net 2 "+3V3")
			(pinfunction "VCC")
			(pintype "power_in")
			(teardrops
				(best_length_ratio 0.2)
				(max_length 1)
				(best_width_ratio 0.9)
				(max_width 2)
				(curved_edges yes)
				(filter_ratio 0.9)
				(enabled yes)
				(allow_two_segments yes)
				(prefer_zone_connections yes)
			)
		)
		(pad "6" smd roundrect
			(at 1.2 -0.95)
			(size 0.8 0.55)
			(layers "F.Cu" "F.Mask" "F.Paste")
			(roundrect_rratio 0.15)
			(net 595 "/Misc/PWM_{SRCSEL}")
			(pinfunction "S")
			(pintype "input")
			(teardrops
				(best_length_ratio 0.2)
				(max_length 1)
				(best_width_ratio 0.9)
				(max_width 2)
				(curved_edges yes)
				(filter_ratio 0.9)
				(enabled yes)
				(allow_two_segments yes)
				(prefer_zone_connections yes)
			)
		)
	)
	(footprint "antmicro-footprints:R_0402_1005Metric"
		(layer "F.Cu")
		(at 129.15 89.510001 -90)
		(descr "Resistor SMD 0402")
		(tags "resistor SMD 0402")
		(property "Reference" "R244"
			(at 0.799999 -0.4 90)
			(layer "F.SilkS")
			(effects
				(font
					(size 0.7 0.7)
					(thickness 0.15)
				)
				(justify right bottom)
			)
		)
		(property "Value" "R_0R_0402"
			(at -1.011843 1.772047 90)
			(layer "F.Fab")
			(effects
				(font
					(size 0.7 0.7)
					(thickness 0.15)
				)
				(justify right bottom)
			)
		)
		(property "Datasheet" "https://industrial.panasonic.com/cdbs/www-data/pdf/RDA0000/AOA0000C301.pdf"
			(at 0 0 270)
			(layer "F.Fab")
			(hide yes)
			(effects
				(font
					(size 1.27 1.27)
					(thickness 0.15)
				)
			)
		)
		(property "Author" "Antmicro"
			(at 39.639999 218.660001 0)
			(layer "F.Fab")
			(hide yes)
			(effects
				(font
					(size 1 1)
					(thickness 0.15)
				)
			)
		)
		(property "Current" "1A"
			(at 39.639999 218.660001 0)
			(layer "F.Fab")
			(hide yes)
			(effects
				(font
					(size 1 1)
					(thickness 0.15)
				)
			)
		)
		(property "License" "Apache-2.0"
			(at 39.639999 218.660001 0)
			(layer "F.Fab")
			(hide yes)
			(effects
				(font
					(size 1 1)
					(thickness 0.15)
				)
			)
		)
		(property "MPN" "ERJ2GE0R00X"
			(at 39.639999 218.660001 0)
			(layer "F.Fab")
			(hide yes)
			(effects
				(font
					(size 1 1)
					(thickness 0.15)
				)
			)
		)
		(property "Manufacturer" "Panasonic"
			(at 39.639999 218.660001 0)
			(layer "F.Fab")
			(hide yes)
			(effects
				(font
					(size 1 1)
					(thickness 0.15)
				)
			)
		)
		(property "Public" "False"
			(at 39.639999 218.660001 0)
			(layer "F.Fab")
			(hide yes)
			(effects
				(font
					(size 1 1)
					(thickness 0.15)
				)
			)
		)
		(property "Tolerance" ""
			(at 39.639999 218.660001 0)
			(layer "F.Fab")
			(hide yes)
			(effects
				(font
					(size 1 1)
					(thickness 0.15)
				)
			)
		)
		(property "Val" "0R"
			(at 39.639999 218.660001 0)
			(layer "F.Fab")
			(hide yes)
			(effects
				(font
					(size 1 1)
					(thickness 0.15)
				)
			)
		)
		(sheetname "GPIO expander")
		(sheetfile "gpio_exp.kicad_sch")
		(attr smd)
		(fp_rect
			(start -0.925 -0.47)
			(end 0.925 0.47)
			(stroke
				(width 0.05)
				(type default)
			)
			(fill no)
			(layer "F.CrtYd")
		)
		(fp_rect
			(start -0.5 -0.25)
			(end 0.5 0.25)
			(stroke
				(width 0.15)
				(type solid)
			)
			(fill no)
			(layer "F.Fab")
		)
		(pad "1" smd roundrect
			(at -0.48 0 270)
			(size 0.59 0.64)
			(layers "F.Cu" "F.Mask" "F.Paste")
			(roundrect_rratio 0.25)
			(net 645 "Net-(U41-IO0_6)")
			(pintype "passive")
			(teardrops
				(best_length_ratio 0.2)
				(max_length 1)
				(best_width_ratio 0.9)
				(max_width 2)
				(curved_edges yes)
				(filter_ratio 0.9)
				(enabled yes)
				(allow_two_segments yes)
				(prefer_zone_connections yes)
			)
		)
		(pad "2" smd roundrect
			(at 0.48 0 270)
			(size 0.59 0.64)
			(layers "F.Cu" "F.Mask" "F.Paste")
			(roundrect_rratio 0.25)
			(net 527 "/Backplane/GPIO")
			(pintype "passive")
			(teardrops
				(best_length_ratio 0.2)
				(max_length 1)
				(best_width_ratio 0.9)
				(max_width 2)
				(curved_edges yes)
				(filter_ratio 0.9)
				(enabled yes)
				(allow_two_segments yes)
				(prefer_zone_connections yes)
			)
		)
	)
	(footprint "antmicro-footprints:C_0402_1005Metric"
		(layer "F.Cu")
		(at 114.35 86.41 90)
		(descr "Capacitor SMD 0402")
		(tags "capacitor SMD 0402")
		(property "Reference" "C8"
			(at 0.8 0.45 90)
			(layer "F.SilkS")
			(effects
				(font
					(size 0.7 0.7)
					(thickness 0.15)
				)
				(justify left bottom)
			)
		)
		(property "Value" "C_1u_0402"
			(at -1.022927 2.155213 90)
			(layer "F.Fab")
			(effects
				(font
					(size 0.7 0.7)
					(thickness 0.15)
				)
				(justify left bottom)
			)
		)
		(property "Datasheet" "https://product.tdk.com/en/search/capacitor/ceramic/mlcc/info?part_no=C1005X6S1A105K050BC"
			(at 0 0 90)
			(layer "F.Fab")
			(hide yes)
			(effects
				(font
					(size 1.27 1.27)
					(thickness 0.15)
				)
			)
		)
		(property "Author" "Antmicro"
			(at 200.76 -27.94 0)
			(layer "F.Fab")
			(hide yes)
			(effects
				(font
					(size 1 1)
					(thickness 0.15)
				)
			)
		)
		(property "Dielectric" ""
			(at 200.76 -27.94 0)
			(layer "F.Fab")
			(hide yes)
			(effects
				(font
					(size 1 1)
					(thickness 0.15)
				)
			)
		)
		(property "License" "Apache-2.0"
			(at 200.76 -27.94 0)
			(layer "F.Fab")
			(hide yes)
			(effects
				(font
					(size 1 1)
					(thickness 0.15)
				)
			)
		)
		(property "MPN" "C1005X6S1A105K050BC"
			(at 200.76 -27.94 0)
			(layer "F.Fab")
			(hide yes)
			(effects
				(font
					(size 1 1)
					(thickness 0.15)
				)
			)
		)
		(property "Manufacturer" "TDK"
			(at 200.76 -27.94 0)
			(layer "F.Fab")
			(hide yes)
			(effects
				(font
					(size 1 1)
					(thickness 0.15)
				)
			)
		)
		(property "Public" "False"
			(at 200.76 -27.94 0)
			(layer "F.Fab")
			(hide yes)
			(effects
				(font
					(size 1 1)
					(thickness 0.15)
				)
			)
		)
		(property "Val" "1u"
			(at 200.76 -27.94 0)
			(layer "F.Fab")
			(hide yes)
			(effects
				(font
					(size 1 1)
					(thickness 0.15)
				)
			)
		)
		(property "Voltage" ""
			(at 200.76 -27.94 0)
			(layer "F.Fab")
			(hide yes)
			(effects
				(font
					(size 1 1)
					(thickness 0.15)
				)
			)
		)
		(sheetname "2xUSB3.0+RJ45")
		(sheetfile "usb3+rj45.kicad_sch")
		(attr smd)
		(fp_rect
			(start -0.925 -0.47)
			(end 0.925 0.47)
			(stroke
				(width 0.05)
				(type default)
			)
			(fill no)
			(layer "F.CrtYd")
		)
		(fp_line
			(start 0.504 -0.25)
			(end 0.504 0.248)
			(stroke
				(width 0.15)
				(type solid)
			)
			(layer "F.Fab")
		)
		(fp_line
			(start -0.494 -0.25)
			(end 0.504 -0.25)
			(stroke
				(width 0.15)
				(type solid)
			)
			(layer "F.Fab")
		)
		(fp_line
			(start 0.504 0.248)
			(end -0.494 0.248)
			(stroke
				(width 0.15)
				(type solid)
			)
			(layer "F.Fab")
		)
		(fp_line
			(start -0.494 0.248)
			(end -0.494 -0.25)
			(stroke
				(width 0.15)
				(type solid)
			)
			(layer "F.Fab")
		)
		(pad "1" smd roundrect
			(at -0.48 0 90)
			(size 0.59 0.64)
			(layers "F.Cu" "F.Mask" "F.Paste")
			(roundrect_rratio 0.25)
			(net 1 "GND")
			(pintype "passive")
			(teardrops
				(best_length_ratio 0.2)
				(max_length 1)
				(best_width_ratio 0.9)
				(max_width 2)
				(curved_edges yes)
				(filter_ratio 0.9)
				(enabled yes)
				(allow_two_segments yes)
				(prefer_zone_connections yes)
			)
		)
		(pad "2" smd roundrect
			(at 0.48 0 90)
			(size 0.59 0.64)
			(layers "F.Cu" "F.Mask" "F.Paste")
			(roundrect_rratio 0.25)
			(net 42 "/2xUSB3.0+RJ45/P1_VBUS")
			(pintype "passive")
			(teardrops
				(best_length_ratio 0.2)
				(max_length 1)
				(best_width_ratio 0.9)
				(max_width 2)
				(curved_edges yes)
				(filter_ratio 0.9)
				(enabled yes)
				(allow_two_segments yes)
				(prefer_zone_connections yes)
			)
		)
	)
	(footprint "antmicro-footprints:R_0402_1005Metric"
		(layer "F.Cu")
		(at 219.73 122.9)
		(descr "Resistor SMD 0402")
		(tags "resistor SMD 0402")
		(property "Reference" "R188"
			(at 0.77 0.46 0)
			(layer "F.SilkS")
			(effects
				(font
					(size 0.7 0.7)
					(thickness 0.15)
				)
				(justify left bottom)
			)
		)
		(property "Value" "R_1k_0402"
			(at -1.011843 1.772047 0)
			(layer "F.Fab")
			(effects
				(font
					(size 0.7 0.7)
					(thickness 0.15)
				)
				(justify left bottom)
			)
		)
		(property "Datasheet" "https://www.bourns.com/docs/product-datasheets/cr.pdf"
			(at 0 0 0)
			(layer "F.Fab")
			(hide yes)
			(effects
				(font
					(size 1.27 1.27)
					(thickness 0.15)
				)
			)
		)
		(property "Author" "Antmicro"
			(at 0 0 0)
			(layer "F.Fab")
			(hide yes)
			(effects
				(font
					(size 1 1)
					(thickness 0.15)
				)
			)
		)
		(property "License" "Apache-2.0"
			(at 0 0 0)
			(layer "F.Fab")
			(hide yes)
			(effects
				(font
					(size 1 1)
					(thickness 0.15)
				)
			)
		)
		(property "MPN" "CR0402-FX-1001GLF"
			(at 0 0 0)
			(layer "F.Fab")
			(hide yes)
			(effects
				(font
					(size 1 1)
					(thickness 0.15)
				)
			)
		)
		(property "Manufacturer" "Bourns"
			(at 0 0 0)
			(layer "F.Fab")
			(hide yes)
			(effects
				(font
					(size 1 1)
					(thickness 0.15)
				)
			)
		)
		(property "Public" "False"
			(at 0 0 0)
			(layer "F.Fab")
			(hide yes)
			(effects
				(font
					(size 1 1)
					(thickness 0.15)
				)
			)
		)
		(property "Tolerance" "1%"
			(at 0 0 0)
			(layer "F.Fab")
			(hide yes)
			(effects
				(font
					(size 1 1)
					(thickness 0.15)
				)
			)
		)
		(property "Val" "1k"
			(at 0 0 0)
			(layer "F.Fab")
			(hide yes)
			(effects
				(font
					(size 1 1)
					(thickness 0.15)
				)
			)
		)
		(sheetname "PCIe misc")
		(sheetfile "pcie_misc.kicad_sch")
		(attr smd dnp)
		(fp_rect
			(start -0.925 -0.47)
			(end 0.925 0.47)
			(stroke
				(width 0.05)
				(type default)
			)
			(fill no)
			(layer "F.CrtYd")
		)
		(fp_rect
			(start -0.5 -0.25)
			(end 0.5 0.25)
			(stroke
				(width 0.15)
				(type solid)
			)
			(fill no)
			(layer "F.Fab")
		)
		(pad "1" smd roundrect
			(at -0.48 0)
			(size 0.59 0.64)
			(layers "F.Cu" "F.Mask" "F.Paste")
			(roundrect_rratio 0.25)
			(net 607 "Net-(U37-~{HIBW_BYPM_LOBW})")
			(pintype "passive")
			(teardrops
				(best_length_ratio 0.2)
				(max_length 1)
				(best_width_ratio 0.9)
				(max_width 2)
				(curved_edges yes)
				(filter_ratio 0.9)
				(enabled yes)
				(allow_two_segments yes)
				(prefer_zone_connections yes)
			)
		)
		(pad "2" smd roundrect
			(at 0.48 0)
			(size 0.59 0.64)
			(layers "F.Cu" "F.Mask" "F.Paste")
			(roundrect_rratio 0.25)
			(net 1 "GND")
			(pintype "passive")
			(teardrops
				(best_length_ratio 0.2)
				(max_length 1)
				(best_width_ratio 0.9)
				(max_width 2)
				(curved_edges yes)
				(filter_ratio 0.9)
				(enabled yes)
				(allow_two_segments yes)
				(prefer_zone_connections yes)
			)
		)
	)
	(footprint "antmicro-footprints:R_0402_1005Metric"
		(layer "F.Cu")
		(at 246.8 132.36 -90)
		(descr "Resistor SMD 0402")
		(tags "resistor SMD 0402")
		(property "Reference" "R175"
			(at 0.85 -0.45 90)
			(layer "F.SilkS")
			(effects
				(font
					(size 0.7 0.7)
					(thickness 0.15)
				)
				(justify right bottom)
			)
		)
		(property "Value" "R_10k_0402"
			(at -1.011843 1.772047 90)
			(layer "F.Fab")
			(effects
				(font
					(size 0.7 0.7)
					(thickness 0.15)
				)
				(justify right bottom)
			)
		)
		(property "Datasheet" "https://www.bourns.com/docs/product-datasheets/cr.pdf"
			(at 0 0 270)
			(layer "F.Fab")
			(hide yes)
			(effects
				(font
					(size 1.27 1.27)
					(thickness 0.15)
				)
			)
		)
		(property "Author" "Antmicro"
			(at 114.44 379.16 0)
			(layer "F.Fab")
			(hide yes)
			(effects
				(font
					(size 1 1)
					(thickness 0.15)
				)
			)
		)
		(property "License" "Apache-2.0"
			(at 114.44 379.16 0)
			(layer "F.Fab")
			(hide yes)
			(effects
				(font
					(size 1 1)
					(thickness 0.15)
				)
			)
		)
		(property "MPN" "CR0402-FX-1002GLF"
			(at 114.44 379.16 0)
			(layer "F.Fab")
			(hide yes)
			(effects
				(font
					(size 1 1)
					(thickness 0.15)
				)
			)
		)
		(property "Manufacturer" "Bourns"
			(at 114.44 379.16 0)
			(layer "F.Fab")
			(hide yes)
			(effects
				(font
					(size 1 1)
					(thickness 0.15)
				)
			)
		)
		(property "Public" "False"
			(at 114.44 379.16 0)
			(layer "F.Fab")
			(hide yes)
			(effects
				(font
					(size 1 1)
					(thickness 0.15)
				)
			)
		)
		(property "Tolerance" "1%"
			(at 114.44 379.16 0)
			(layer "F.Fab")
			(hide yes)
			(effects
				(font
					(size 1 1)
					(thickness 0.15)
				)
			)
		)
		(property "Val" "10k"
			(at 114.44 379.16 0)
			(layer "F.Fab")
			(hide yes)
			(effects
				(font
					(size 1 1)
					(thickness 0.15)
				)
			)
		)
		(sheetname "Com Express 7 MGMT")
		(sheetfile "com_express_7_mgmt.kicad_sch")
		(attr smd dnp)
		(fp_rect
			(start -0.925 -0.47)
			(end 0.925 0.47)
			(stroke
				(width 0.05)
				(type default)
			)
			(fill no)
			(layer "F.CrtYd")
		)
		(fp_rect
			(start -0.5 -0.25)
			(end 0.5 0.25)
			(stroke
				(width 0.15)
				(type solid)
			)
			(fill no)
			(layer "F.Fab")
		)
		(pad "1" smd roundrect
			(at -0.48 0 270)
			(size 0.59 0.64)
			(layers "F.Cu" "F.Mask" "F.Paste")
			(roundrect_rratio 0.25)
			(net 872 "Net-(U34-~{KILL})")
			(pintype "passive")
			(teardrops
				(best_length_ratio 0.2)
				(max_length 1)
				(best_width_ratio 0.9)
				(max_width 2)
				(curved_edges yes)
				(filter_ratio 0.9)
				(enabled yes)
				(allow_two_segments yes)
				(prefer_zone_connections yes)
			)
		)
		(pad "2" smd roundrect
			(at 0.48 0 270)
			(size 0.59 0.64)
			(layers "F.Cu" "F.Mask" "F.Paste")
			(roundrect_rratio 0.25)
			(net 73 "+3V3_AON")
			(pintype "passive")
			(teardrops
				(best_length_ratio 0.2)
				(max_length 1)
				(best_width_ratio 0.9)
				(max_width 2)
				(curved_edges yes)
				(filter_ratio 0.9)
				(enabled yes)
				(allow_two_segments yes)
				(prefer_zone_connections yes)
			)
		)
	)
)
